(kicad_pcb
	(version 20260206)
	(generator "pcbnew")
	(generator_version "10.0")
	(general
		(thickness 1.6)
		(legacy_teardrops no)
	)
	(paper "A4")
	(title_block
		(title "peb — Lightning_PEB_BRD.brd")
		(comment 1 "Lightning (Wiwynn / Facebook NVMe JBOF) / footprints 648-655 of 2563")
	)
	(layers
		(0 "F.Cu" signal "TOP")
		(4 "In1.Cu" signal "L2GND")
		(6 "In2.Cu" signal "L3")
		(8 "In3.Cu" signal "L4VCC")
		(10 "In4.Cu" signal "L5VCC")
		(12 "In5.Cu" signal "L6")
		(14 "In6.Cu" signal "L7GND")
		(2 "B.Cu" signal "BOTTOM")
		(9 "F.Adhes" user "F.Adhesive")
		(11 "B.Adhes" user "B.Adhesive")
		(13 "F.Paste" user "Package Geometry/Pastemask Top")
		(15 "B.Paste" user "Package Geometry/Pastemask Bottom")
		(5 "F.SilkS" user "Ref Des/Silkscreen Top")
		(7 "B.SilkS" user "Ref Des/Silkscreen Bottom")
		(1 "F.Mask" user "Board Geometry/Soldermask Top")
		(3 "B.Mask" user "Board Geometry/Soldermask Bottom")
		(17 "Dwgs.User" user "User.Drawings")
		(19 "Cmts.User" user "User.Comments")
		(21 "Eco1.User" user "User.Eco1")
		(23 "Eco2.User" user "User.Eco2")
		(25 "Edge.Cuts" user "Board Geometry/Outline")
		(27 "Margin" user)
		(31 "F.CrtYd" user "Package Geometry/Place Bound Top")
		(29 "B.CrtYd" user "Package Geometry/Place Bound Bottom")
		(35 "F.Fab" user "Ref Des/Assembly Top")
		(33 "B.Fab" user "Ref Des/Assembly Bottom")
	)
	(footprint ""
		(layer "F.Cu")
		(at 166.116 -86.3854 90)
		(property "Reference" "R55"
			(at 0 0 90)
			(layer "F.SilkS")
			(hide yes)
			(effects
				(font
					(size 1.27 1.27)
				)
			)
		)
		(property "Value" "10KR2F-2-GP"
			(at 0.064008 -3.993896 90)
			(unlocked yes)
			(layer "F.Fab")
			(hide yes)
			(effects
				(font
					(size 1.016 1.016)
					(thickness 0.1524)
				)
			)
		)
		(property "Device Type" "R402H16"
			(at 0.064008 -5.517896 90)
			(unlocked yes)
			(layer "F.Fab")
			(hide yes)
			(effects
				(font
					(size 1.016 1.016)
					(thickness 0.1524)
				)
			)
		)
		(duplicate_pad_numbers_are_jumpers no)
		(fp_line
			(start 0.508 -0.9398)
			(end -0.508 -0.9398)
			(stroke
				(width 0.1524)
				(type default)
			)
			(layer "F.SilkS")
		)
		(fp_line
			(start -0.508 -0.9398)
			(end -0.508 0.9398)
			(stroke
				(width 0.1524)
				(type default)
			)
			(layer "F.SilkS")
		)
		(fp_rect
			(start -0.508 0.9398)
			(end 0.508 -0.9398)
			(stroke
				(width 0)
				(type default)
			)
			(fill no)
			(layer "F.CrtYd")
		)
		(fp_rect
			(start -0.508 0.9398)
			(end 0.508 -0.9398)
			(stroke
				(width 0)
				(type default)
			)
			(fill no)
			(layer "F.Fab")
		)
		(pad "1" smd custom
			(at 0 -0.4445 90)
			(size 0.1397 0.1397)
			(layers "F.Cu" "F.Mask" "F.Paste")
			(net "GND")
			(options
				(clearance outline)
				(anchor circle)
			)
			(primitives
				(gr_poly
					(pts
						(arc
							(start -0.1778 -0.2794)
							(mid -0.249642 -0.249642)
							(end -0.2794 -0.1778)
						)
						(arc
							(start -0.2794 0.1778)
							(mid -0.249642 0.249642)
							(end -0.1778 0.2794)
						)
						(arc
							(start 0.1778 0.2794)
							(mid 0.249642 0.249642)
							(end 0.2794 0.1778)
						)
						(arc
							(start 0.2794 -0.1778)
							(mid 0.249642 -0.249642)
							(end 0.1778 -0.2794)
						)
					)
					(width 0)
					(fill yes)
				)
			)
		)
		(pad "2" smd custom
			(at 0 0.4445 90)
			(size 0.1397 0.1397)
			(layers "F.Cu" "F.Mask" "F.Paste")
			(net "CLKGEN_OE1")
			(options
				(clearance outline)
				(anchor circle)
			)
			(primitives
				(gr_poly
					(pts
						(arc
							(start -0.1778 -0.2794)
							(mid -0.249642 -0.249642)
							(end -0.2794 -0.1778)
						)
						(arc
							(start -0.2794 0.1778)
							(mid -0.249642 0.249642)
							(end -0.1778 0.2794)
						)
						(arc
							(start 0.1778 0.2794)
							(mid 0.249642 0.249642)
							(end 0.2794 0.1778)
						)
						(arc
							(start 0.2794 -0.1778)
							(mid 0.249642 -0.249642)
							(end 0.1778 -0.2794)
						)
					)
					(width 0)
					(fill yes)
				)
			)
		)
	)
	(footprint ""
		(layer "F.Cu")
		(at 83.808062 -212.420454 180)
		(property "Reference" "C350"
			(at 0 0 180)
			(layer "F.SilkS")
			(hide yes)
			(effects
				(font
					(size 1.27 1.27)
				)
			)
		)
		(property "Value" "SCD22U10V2KX-1GP"
			(at 1.1811 -2.7051 180)
			(unlocked yes)
			(layer "F.Fab")
			(hide yes)
			(effects
				(font
					(size 1.016 1.016)
					(thickness 0.1524)
				)
			)
		)
		(property "Device Type" "C402H22"
			(at 1.1811 -4.2291 180)
			(unlocked yes)
			(layer "F.Fab")
			(hide yes)
			(effects
				(font
					(size 1.016 1.016)
					(thickness 0.1524)
				)
			)
		)
		(duplicate_pad_numbers_are_jumpers no)
		(fp_rect
			(start -0.4318 0.9525)
			(end 0.4318 -0.9525)
			(stroke
				(width 0)
				(type default)
			)
			(fill no)
			(layer "F.CrtYd")
		)
		(fp_rect
			(start -0.4318 0.9525)
			(end 0.4318 -0.9525)
			(stroke
				(width 0)
				(type default)
			)
			(fill no)
			(layer "F.Fab")
		)
		(pad "1" smd custom
			(at 0 -0.4445 180)
			(size 0.1524 0.1524)
			(layers "F.Cu" "F.Mask" "F.Paste")
			(net "PCIE_TX_CAP_N67")
			(options
				(clearance outline)
				(anchor circle)
			)
			(primitives
				(gr_poly
					(pts
						(arc
							(start 0.3048 -0.2032)
							(mid 0.275042 -0.275042)
							(end 0.2032 -0.3048)
						)
						(arc
							(start -0.2032 -0.3048)
							(mid -0.275042 -0.275042)
							(end -0.3048 -0.2032)
						)
						(arc
							(start -0.3048 0.2032)
							(mid -0.275042 0.275042)
							(end -0.2032 0.3048)
						)
						(arc
							(start 0.2032 0.3048)
							(mid 0.275042 0.275042)
							(end 0.3048 0.2032)
						)
					)
					(width 0)
					(fill yes)
				)
			)
		)
		(pad "2" smd custom
			(at 0 0.4445 180)
			(size 0.1524 0.1524)
			(layers "F.Cu" "F.Mask" "F.Paste")
			(net "PCIE_TX_N67")
			(options
				(clearance outline)
				(anchor circle)
			)
			(primitives
				(gr_poly
					(pts
						(arc
							(start 0.3048 -0.2032)
							(mid 0.275042 -0.275042)
							(end 0.2032 -0.3048)
						)
						(arc
							(start -0.2032 -0.3048)
							(mid -0.275042 -0.275042)
							(end -0.3048 -0.2032)
						)
						(arc
							(start -0.3048 0.2032)
							(mid -0.275042 0.275042)
							(end -0.2032 0.3048)
						)
						(arc
							(start 0.2032 0.3048)
							(mid 0.275042 0.275042)
							(end 0.3048 0.2032)
						)
					)
					(width 0)
					(fill yes)
				)
			)
		)
	)
	(footprint ""
		(layer "F.Cu")
		(at 144.792192 -212.420454 180)
		(property "Reference" "C315"
			(at 0 0 180)
			(layer "F.SilkS")
			(hide yes)
			(effects
				(font
					(size 1.27 1.27)
				)
			)
		)
		(property "Value" "SCD22U10V2KX-1GP"
			(at 1.1811 -2.7051 180)
			(unlocked yes)
			(layer "F.Fab")
			(hide yes)
			(effects
				(font
					(size 1.016 1.016)
					(thickness 0.1524)
				)
			)
		)
		(property "Device Type" "C402H22"
			(at 1.1811 -4.2291 180)
			(unlocked yes)
			(layer "F.Fab")
			(hide yes)
			(effects
				(font
					(size 1.016 1.016)
					(thickness 0.1524)
				)
			)
		)
		(duplicate_pad_numbers_are_jumpers no)
		(fp_rect
			(start -0.4318 0.9525)
			(end 0.4318 -0.9525)
			(stroke
				(width 0)
				(type default)
			)
			(fill no)
			(layer "F.CrtYd")
		)
		(fp_rect
			(start -0.4318 0.9525)
			(end 0.4318 -0.9525)
			(stroke
				(width 0)
				(type default)
			)
			(fill no)
			(layer "F.Fab")
		)
		(pad "1" smd custom
			(at 0 -0.4445 180)
			(size 0.1524 0.1524)
			(layers "F.Cu" "F.Mask" "F.Paste")
			(net "PCIE_TX_CAP_P57")
			(options
				(clearance outline)
				(anchor circle)
			)
			(primitives
				(gr_poly
					(pts
						(arc
							(start 0.3048 -0.2032)
							(mid 0.275042 -0.275042)
							(end 0.2032 -0.3048)
						)
						(arc
							(start -0.2032 -0.3048)
							(mid -0.275042 -0.275042)
							(end -0.3048 -0.2032)
						)
						(arc
							(start -0.3048 0.2032)
							(mid -0.275042 0.275042)
							(end -0.2032 0.3048)
						)
						(arc
							(start 0.2032 0.3048)
							(mid 0.275042 0.275042)
							(end 0.3048 0.2032)
						)
					)
					(width 0)
					(fill yes)
				)
			)
		)
		(pad "2" smd custom
			(at 0 0.4445 180)
			(size 0.1524 0.1524)
			(layers "F.Cu" "F.Mask" "F.Paste")
			(net "PCIE_TX_P57")
			(options
				(clearance outline)
				(anchor circle)
			)
			(primitives
				(gr_poly
					(pts
						(arc
							(start 0.3048 -0.2032)
							(mid 0.275042 -0.275042)
							(end 0.2032 -0.3048)
						)
						(arc
							(start -0.2032 -0.3048)
							(mid -0.275042 -0.275042)
							(end -0.3048 -0.2032)
						)
						(arc
							(start -0.3048 0.2032)
							(mid -0.275042 0.275042)
							(end -0.2032 0.3048)
						)
						(arc
							(start 0.2032 0.3048)
							(mid 0.275042 0.275042)
							(end 0.3048 0.2032)
						)
					)
					(width 0)
					(fill yes)
				)
			)
		)
	)
	(footprint ""
		(layer "F.Cu")
		(at 8.128 -120.65)
		(property "Reference" "R15"
			(at 0 0 0)
			(layer "F.SilkS")
			(hide yes)
			(effects
				(font
					(size 1.27 1.27)
				)
			)
		)
		(property "Value" "0R2J-2-GP"
			(at 0.064008 -3.993896 0)
			(unlocked yes)
			(layer "F.Fab")
			(hide yes)
			(effects
				(font
					(size 1.016 1.016)
					(thickness 0.1524)
				)
			)
		)
		(property "Device Type" "R402H16"
			(at 0.064008 -5.517896 0)
			(unlocked yes)
			(layer "F.Fab")
			(hide yes)
			(effects
				(font
					(size 1.016 1.016)
					(thickness 0.1524)
				)
			)
		)
		(duplicate_pad_numbers_are_jumpers no)
		(fp_line
			(start -0.508 -0.9398)
			(end -0.508 0.9398)
			(stroke
				(width 0.1524)
				(type default)
			)
			(layer "F.SilkS")
		)
		(fp_line
			(start 0.508 -0.9398)
			(end -0.508 -0.9398)
			(stroke
				(width 0.1524)
				(type default)
			)
			(layer "F.SilkS")
		)
		(fp_rect
			(start -0.508 0.9398)
			(end 0.508 -0.9398)
			(stroke
				(width 0)
				(type default)
			)
			(fill no)
			(layer "F.CrtYd")
		)
		(fp_rect
			(start -0.508 0.9398)
			(end 0.508 -0.9398)
			(stroke
				(width 0)
				(type default)
			)
			(fill no)
			(layer "F.Fab")
		)
		(pad "1" smd custom
			(at 0 -0.4445)
			(size 0.1397 0.1397)
			(layers "F.Cu" "F.Mask" "F.Paste")
			(net "BMC_I2C1_MINI1_SDA")
			(options
				(clearance outline)
				(anchor circle)
			)
			(primitives
				(gr_poly
					(pts
						(arc
							(start -0.1778 -0.2794)
							(mid -0.249642 -0.249642)
							(end -0.2794 -0.1778)
						)
						(arc
							(start -0.2794 0.1778)
							(mid -0.249642 0.249642)
							(end -0.1778 0.2794)
						)
						(arc
							(start 0.1778 0.2794)
							(mid 0.249642 0.249642)
							(end 0.2794 0.1778)
						)
						(arc
							(start 0.2794 -0.1778)
							(mid 0.249642 -0.249642)
							(end 0.1778 -0.2794)
						)
					)
					(width 0)
					(fill yes)
				)
			)
		)
		(pad "2" smd custom
			(at 0 0.4445)
			(size 0.1397 0.1397)
			(layers "F.Cu" "F.Mask" "F.Paste")
			(net "BMC_I2C1_MINI1_SDA_S")
			(options
				(clearance outline)
				(anchor circle)
			)
			(primitives
				(gr_poly
					(pts
						(arc
							(start -0.1778 -0.2794)
							(mid -0.249642 -0.249642)
							(end -0.2794 -0.1778)
						)
						(arc
							(start -0.2794 0.1778)
							(mid -0.249642 0.249642)
							(end -0.1778 0.2794)
						)
						(arc
							(start 0.1778 0.2794)
							(mid 0.249642 0.249642)
							(end 0.2794 0.1778)
						)
						(arc
							(start 0.2794 -0.1778)
							(mid 0.249642 -0.249642)
							(end 0.1778 -0.2794)
						)
					)
					(width 0)
					(fill yes)
				)
			)
		)
	)
	(footprint ""
		(layer "F.Cu")
		(at 168.021 -95.6564 90)
		(property "Reference" "R59"
			(at 0 0 90)
			(layer "F.SilkS")
			(hide yes)
			(effects
				(font
					(size 1.27 1.27)
				)
			)
		)
		(property "Value" "10KR2F-2-GP"
			(at 0.064008 -3.993896 90)
			(unlocked yes)
			(layer "F.Fab")
			(hide yes)
			(effects
				(font
					(size 1.016 1.016)
					(thickness 0.1524)
				)
			)
		)
		(property "Device Type" "R402H16"
			(at 0.064008 -5.517896 90)
			(unlocked yes)
			(layer "F.Fab")
			(hide yes)
			(effects
				(font
					(size 1.016 1.016)
					(thickness 0.1524)
				)
			)
		)
		(duplicate_pad_numbers_are_jumpers no)
		(fp_line
			(start 0.508 -0.9398)
			(end -0.508 -0.9398)
			(stroke
				(width 0.1524)
				(type default)
			)
			(layer "F.SilkS")
		)
		(fp_line
			(start -0.508 -0.9398)
			(end -0.508 0.9398)
			(stroke
				(width 0.1524)
				(type default)
			)
			(layer "F.SilkS")
		)
		(fp_rect
			(start -0.508 0.9398)
			(end 0.508 -0.9398)
			(stroke
				(width 0)
				(type default)
			)
			(fill no)
			(layer "F.CrtYd")
		)
		(fp_rect
			(start -0.508 0.9398)
			(end 0.508 -0.9398)
			(stroke
				(width 0)
				(type default)
			)
			(fill no)
			(layer "F.Fab")
		)
		(pad "1" smd custom
			(at 0 -0.4445 90)
			(size 0.1397 0.1397)
			(layers "F.Cu" "F.Mask" "F.Paste")
			(net "CLKGEN_OE2")
			(options
				(clearance outline)
				(anchor circle)
			)
			(primitives
				(gr_poly
					(pts
						(arc
							(start -0.1778 -0.2794)
							(mid -0.249642 -0.249642)
							(end -0.2794 -0.1778)
						)
						(arc
							(start -0.2794 0.1778)
							(mid -0.249642 0.249642)
							(end -0.1778 0.2794)
						)
						(arc
							(start 0.1778 0.2794)
							(mid 0.249642 0.249642)
							(end 0.2794 0.1778)
						)
						(arc
							(start 0.2794 -0.1778)
							(mid 0.249642 -0.249642)
							(end 0.1778 -0.2794)
						)
					)
					(width 0)
					(fill yes)
				)
			)
		)
		(pad "2" smd custom
			(at 0 0.4445 90)
			(size 0.1397 0.1397)
			(layers "F.Cu" "F.Mask" "F.Paste")
			(net "P1V8_CLKGEN")
			(options
				(clearance outline)
				(anchor circle)
			)
			(primitives
				(gr_poly
					(pts
						(arc
							(start -0.1778 -0.2794)
							(mid -0.249642 -0.249642)
							(end -0.2794 -0.1778)
						)
						(arc
							(start -0.2794 0.1778)
							(mid -0.249642 0.249642)
							(end -0.1778 0.2794)
						)
						(arc
							(start 0.1778 0.2794)
							(mid 0.249642 0.249642)
							(end 0.2794 0.1778)
						)
						(arc
							(start 0.2794 -0.1778)
							(mid 0.249642 -0.249642)
							(end 0.1778 -0.2794)
						)
					)
					(width 0)
					(fill yes)
				)
			)
		)
	)
	(footprint ""
		(layer "F.Cu")
		(at 9.906 -194.3354 180)
		(property "Reference" "R2103"
			(at 0 0 180)
			(layer "F.SilkS")
			(hide yes)
			(effects
				(font
					(size 1.27 1.27)
				)
			)
		)
		(property "Value" "150KR2J-GP"
			(at 0.064008 -3.993896 180)
			(unlocked yes)
			(layer "F.Fab")
			(hide yes)
			(effects
				(font
					(size 1.016 1.016)
					(thickness 0.1524)
				)
			)
		)
		(property "Device Type" "R402H16"
			(at 0.064008 -5.517896 180)
			(unlocked yes)
			(layer "F.Fab")
			(hide yes)
			(effects
				(font
					(size 1.016 1.016)
					(thickness 0.1524)
				)
			)
		)
		(duplicate_pad_numbers_are_jumpers no)
		(fp_line
			(start 0.508 -0.9398)
			(end -0.508 -0.9398)
			(stroke
				(width 0.1524)
				(type default)
			)
			(layer "F.SilkS")
		)
		(fp_line
			(start -0.508 -0.9398)
			(end -0.508 0.9398)
			(stroke
				(width 0.1524)
				(type default)
			)
			(layer "F.SilkS")
		)
		(fp_rect
			(start -0.508 0.9398)
			(end 0.508 -0.9398)
			(stroke
				(width 0)
				(type default)
			)
			(fill no)
			(layer "F.CrtYd")
		)
		(fp_rect
			(start -0.508 0.9398)
			(end 0.508 -0.9398)
			(stroke
				(width 0)
				(type default)
			)
			(fill no)
			(layer "F.Fab")
		)
		(pad "1" smd custom
			(at 0 -0.4445 180)
			(size 0.1397 0.1397)
			(layers "F.Cu" "F.Mask" "F.Paste")
			(net "MB0_CM_ADR1_R")
			(options
				(clearance outline)
				(anchor circle)
			)
			(primitives
				(gr_poly
					(pts
						(arc
							(start -0.1778 -0.2794)
							(mid -0.249642 -0.249642)
							(end -0.2794 -0.1778)
						)
						(arc
							(start -0.2794 0.1778)
							(mid -0.249642 0.249642)
							(end -0.1778 0.2794)
						)
						(arc
							(start 0.1778 0.2794)
							(mid 0.249642 0.249642)
							(end 0.2794 0.1778)
						)
						(arc
							(start 0.2794 -0.1778)
							(mid 0.249642 -0.249642)
							(end 0.1778 -0.2794)
						)
					)
					(width 0)
					(fill yes)
				)
			)
		)
		(pad "2" smd custom
			(at 0 0.4445 180)
			(size 0.1397 0.1397)
			(layers "F.Cu" "F.Mask" "F.Paste")
			(net "AGND_CURRENT_MON")
			(options
				(clearance outline)
				(anchor circle)
			)
			(primitives
				(gr_poly
					(pts
						(arc
							(start -0.1778 -0.2794)
							(mid -0.249642 -0.249642)
							(end -0.2794 -0.1778)
						)
						(arc
							(start -0.2794 0.1778)
							(mid -0.249642 0.249642)
							(end -0.1778 0.2794)
						)
						(arc
							(start 0.1778 0.2794)
							(mid 0.249642 0.249642)
							(end 0.2794 0.1778)
						)
						(arc
							(start 0.2794 -0.1778)
							(mid 0.249642 -0.249642)
							(end 0.1778 -0.2794)
						)
					)
					(width 0)
					(fill yes)
				)
			)
		)
	)
	(footprint ""
		(layer "F.Cu")
		(at 25.273 -70.1802 -90)
		(property "Reference" "R406"
			(at 0 0 270)
			(layer "F.SilkS")
			(hide yes)
			(effects
				(font
					(size 1.27 1.27)
				)
			)
		)
		(property "Value" "3K3R2F-2-GP"
			(at 0.064008 -3.993896 270)
			(unlocked yes)
			(layer "F.Fab")
			(hide yes)
			(effects
				(font
					(size 1.016 1.016)
					(thickness 0.1524)
				)
			)
		)
		(property "Device Type" "R402H16"
			(at 0.064008 -5.517896 270)
			(unlocked yes)
			(layer "F.Fab")
			(hide yes)
			(effects
				(font
					(size 1.016 1.016)
					(thickness 0.1524)
				)
			)
		)
		(duplicate_pad_numbers_are_jumpers no)
		(fp_line
			(start -0.508 -0.9398)
			(end -0.508 0.9398)
			(stroke
				(width 0.1524)
				(type default)
			)
			(layer "F.SilkS")
		)
		(fp_line
			(start 0.508 -0.9398)
			(end -0.508 -0.9398)
			(stroke
				(width 0.1524)
				(type default)
			)
			(layer "F.SilkS")
		)
		(fp_rect
			(start -0.508 0.9398)
			(end 0.508 -0.9398)
			(stroke
				(width 0)
				(type default)
			)
			(fill no)
			(layer "F.CrtYd")
		)
		(fp_rect
			(start -0.508 0.9398)
			(end 0.508 -0.9398)
			(stroke
				(width 0)
				(type default)
			)
			(fill no)
			(layer "F.Fab")
		)
		(pad "1" smd custom
			(at 0 -0.4445 270)
			(size 0.1397 0.1397)
			(layers "F.Cu" "F.Mask" "F.Paste")
			(net "P3V3_STBY")
			(options
				(clearance outline)
				(anchor circle)
			)
			(primitives
				(gr_poly
					(pts
						(arc
							(start -0.1778 -0.2794)
							(mid -0.249642 -0.249642)
							(end -0.2794 -0.1778)
						)
						(arc
							(start -0.2794 0.1778)
							(mid -0.249642 0.249642)
							(end -0.1778 0.2794)
						)
						(arc
							(start 0.1778 0.2794)
							(mid 0.249642 0.249642)
							(end 0.2794 0.1778)
						)
						(arc
							(start 0.2794 -0.1778)
							(mid 0.249642 -0.249642)
							(end 0.1778 -0.2794)
						)
					)
					(width 0)
					(fill yes)
				)
			)
		)
		(pad "2" smd custom
			(at 0 0.4445 270)
			(size 0.1397 0.1397)
			(layers "F.Cu" "F.Mask" "F.Paste")
			(net "LAN_MAIN_PWR_OK")
			(options
				(clearance outline)
				(anchor circle)
			)
			(primitives
				(gr_poly
					(pts
						(arc
							(start -0.1778 -0.2794)
							(mid -0.249642 -0.249642)
							(end -0.2794 -0.1778)
						)
						(arc
							(start -0.2794 0.1778)
							(mid -0.249642 0.249642)
							(end -0.1778 0.2794)
						)
						(arc
							(start 0.1778 0.2794)
							(mid 0.249642 0.249642)
							(end 0.2794 0.1778)
						)
						(arc
							(start 0.2794 -0.1778)
							(mid 0.249642 -0.249642)
							(end 0.1778 -0.2794)
						)
					)
					(width 0)
					(fill yes)
				)
			)
		)
	)
	(footprint ""
		(layer "F.Cu")
		(at 182.0164 -61.595)
		(property "Reference" "C560"
			(at 0 0 0)
			(layer "F.SilkS")
			(hide yes)
			(effects
				(font
					(size 1.27 1.27)
				)
			)
		)
		(property "Value" "SC4D7U16V5KX-1-GP"
			(at -0.0762 -6.1214 0)
			(unlocked yes)
			(layer "F.Fab")
			(hide yes)
			(effects
				(font
					(size 1.016 1.016)
					(thickness 0.1524)
				)
			)
		)
		(property "Device Type" "C805H56"
			(at -0.0762 -8.1534 0)
			(unlocked yes)
			(layer "F.Fab")
			(hide yes)
			(effects
				(font
					(size 1.016 1.016)
					(thickness 0.1524)
				)
			)
		)
		(duplicate_pad_numbers_are_jumpers no)
		(fp_line
			(start 0.635 0)
			(end -0.635 0)
			(stroke
				(width 0.508)
				(type default)
			)
			(layer "F.SilkS")
		)
		(fp_rect
			(start -0.9652 1.778)
			(end 0.9652 -1.778)
			(stroke
				(width 0)
				(type default)
			)
			(fill no)
			(layer "F.CrtYd")
		)
		(fp_poly
			(pts
				(xy -0.9652 -1.778) (xy 0.9652 -1.778) (xy 0.9652 1.778) (xy -0.9652 1.778)
			)
			(stroke
				(width 0)
				(type default)
			)
			(fill no)
			(layer "F.Fab")
		)
		(pad "1" smd rect
			(at 0 -0.9652)
			(size 1.397 1.143)
			(layers "F.Cu" "F.Mask" "F.Paste")
			(net "DUT_AVD_PCIE")
		)
		(pad "2" smd rect
			(at 0 0.9652)
			(size 1.397 1.143)
			(layers "F.Cu" "F.Mask" "F.Paste")
			(net "GND")
		)
	)
)
